(kicad_pcb
	(version 20260206)
	(generator "pcbnew")
	(generator_version "10.0")
	(general
		(thickness 1.6)
		(legacy_teardrops no)
	)
	(paper "A4")
	(title_block
		(title "03242023_DA0F0TMBIJ0_F0T_Motherboard_J_brd_V01_OCP.brd")
		(comment 1 "Grand Teton / footprint 3077 of 6105 (J41), pads 1-107 of 175")
	)
	(layers
		(0 "F.Cu" signal "TOP")
		(4 "In1.Cu" signal "GND")
		(6 "In2.Cu" signal "IN1")
		(8 "In3.Cu" signal "GND1")
		(10 "In4.Cu" signal "IN2")
		(12 "In5.Cu" signal "GND2")
		(14 "In6.Cu" signal "IN3")
		(16 "In7.Cu" signal "GND3")
		(18 "In8.Cu" signal "VCC")
		(20 "In9.Cu" signal "VCC1")
		(22 "In10.Cu" signal "GND4")
		(24 "In11.Cu" signal "IN4")
		(26 "In12.Cu" signal "GND5")
		(28 "In13.Cu" signal "IN5")
		(30 "In14.Cu" signal "GND6")
		(32 "In15.Cu" signal "IN6")
		(34 "In16.Cu" signal "GND7")
		(2 "B.Cu" signal "BOTTOM")
		(9 "F.Adhes" user "F.Adhesive")
		(11 "B.Adhes" user "B.Adhesive")
		(13 "F.Paste" user "Package Geometry/Pastemask Top")
		(15 "B.Paste" user "Package Geometry/Pastemask Bottom")
		(5 "F.SilkS" user "Ref Des/Silkscreen Top")
		(7 "B.SilkS" user "Ref Des/Silkscreen Bottom")
		(1 "F.Mask" user "Board Geometry/Soldermask Top")
		(3 "B.Mask" user "Board Geometry/Soldermask Bottom")
		(17 "Dwgs.User" user "User.Drawings")
		(19 "Cmts.User" user "User.Comments")
		(21 "Eco1.User" user "User.Eco1")
		(23 "Eco2.User" user "User.Eco2")
		(25 "Edge.Cuts" user "Board Geometry/Outline")
		(27 "Margin" user)
		(31 "F.CrtYd" user "Package Geometry/Place Bound Top")
		(29 "B.CrtYd" user "Package Geometry/Place Bound Bottom")
		(35 "F.Fab" user "Ref Des/Assembly Top")
		(33 "B.Fab" user "Ref Des/Assembly Bottom")
	)
	(footprint ""
		(layer "F.Cu")
		(at 160.402016 -10.850118 -90)
		(property "Reference" "J41"
			(at -12.075414 24.511762 0)
			(unlocked yes)
			(layer "F.SilkS")
			(effects
				(font
					(size 0.7874 0.5842)
					(thickness 0.1524)
				)
				(justify left)
			)
		)
		(property "Value" ""
			(at 0 0 270)
			(layer "F.Fab")
			(effects
				(font
					(size 1.27 1.27)
				)
			)
		)
		(duplicate_pad_numbers_are_jumpers no)
		(pad "" np_thru_hole circle
			(at -0.599948 -32.079946 180)
			(size 1.1176 1.1176)
			(drill 1.1176)
			(layers "*.Cu" "*.Mask")
			(clearance 0.381)
			(thermal_gap 0.381)
		)
		(pad "" np_thru_hole circle
			(at 0.40005 32.085026 180)
			(size 1.1176 1.1176)
			(drill 1.1176)
			(layers "*.Cu" "*.Mask")
			(clearance 0.381)
			(thermal_gap 0.381)
		)
		(pad "A1" smd rect
			(at -2.750058 -18.465038 180)
			(size 0.381 1.4478)
			(layers "F.Cu" "F.Mask" "F.Paste")
			(net "SMB_OCP_SFF_3V3AUX_SCL_R0")
		)
		(pad "A2" smd rect
			(at -2.750058 -17.86509 180)
			(size 0.381 1.4478)
			(layers "F.Cu" "F.Mask" "F.Paste")
			(net "SMB_OCP_SFF_3V3AUX_SDA_R0")
		)
		(pad "A3" smd rect
			(at -2.750058 -17.264888 180)
			(size 0.381 1.4478)
			(layers "F.Cu" "F.Mask" "F.Paste")
			(net "SMB_HOST_3V3AUX_SCL_R0")
		)
		(pad "A4" smd rect
			(at -2.750058 -16.66494 180)
			(size 0.381 1.4478)
			(layers "F.Cu" "F.Mask" "F.Paste")
			(net "SMB_HOST_3V3AUX_SDA_R0")
		)
		(pad "A5" smd rect
			(at -2.750058 -16.064992 180)
			(size 0.381 1.4478)
			(layers "F.Cu" "F.Mask" "F.Paste")
			(net "SMB_VR_3V3AUX_SCL_R0")
		)
		(pad "A6" smd rect
			(at -2.750058 -15.465044 180)
			(size 0.381 1.4478)
			(layers "F.Cu" "F.Mask" "F.Paste")
			(net "SMB_VR_3V3AUX_SDA_R0")
		)
		(pad "A7" smd rect
			(at -2.750058 -14.865096 180)
			(size 0.381 1.4478)
			(layers "F.Cu" "F.Mask" "F.Paste")
			(net "SMB_SML1_PMBUS_3V3AUX_PCH_SCL_R")
		)
		(pad "A8" smd rect
			(at -2.750058 -14.264894 180)
			(size 0.381 1.4478)
			(layers "F.Cu" "F.Mask" "F.Paste")
			(net "SMB_SML1_PMBUS_3V3AUX_PCH_SDA_R")
		)
		(pad "A9" smd rect
			(at -2.750058 -13.664946 180)
			(size 0.381 1.4478)
			(layers "F.Cu" "F.Mask" "F.Paste")
			(net "I3C_BMC_SWB_SCL")
		)
		(pad "A10" smd rect
			(at -2.750058 -13.064998 180)
			(size 0.381 1.4478)
			(layers "F.Cu" "F.Mask" "F.Paste")
			(net "I3C_BMC_SWB_SDA")
		)
		(pad "A11" smd rect
			(at -2.750058 -12.46505 180)
			(size 0.381 1.4478)
			(layers "F.Cu" "F.Mask" "F.Paste")
			(net "SMB_OCP_V3_2_3V3AUX_SCL_R0")
		)
		(pad "A12" smd rect
			(at -2.750058 -11.865102 180)
			(size 0.381 1.4478)
			(layers "F.Cu" "F.Mask" "F.Paste")
			(net "SMB_OCP_V3_2_3V3AUX_SDA_R0")
		)
		(pad "A13" smd rect
			(at -2.750058 -11.2649 180)
			(size 0.381 1.4478)
			(layers "F.Cu" "F.Mask" "F.Paste")
			(net "GND")
		)
		(pad "A14" smd rect
			(at -2.750058 -10.664952 180)
			(size 0.381 1.4478)
			(layers "F.Cu" "F.Mask" "F.Paste")
			(net "CLK_100M_BMC_P3E_DP_R")
		)
		(pad "A15" smd rect
			(at -2.750058 -10.065004 180)
			(size 0.381 1.4478)
			(layers "F.Cu" "F.Mask" "F.Paste")
			(net "CLK_100M_BMC_P3E_DN_R")
		)
		(pad "A16" smd rect
			(at -2.750058 -9.465056 180)
			(size 0.381 1.4478)
			(layers "F.Cu" "F.Mask" "F.Paste")
			(net "GND")
		)
		(pad "A17" smd rect
			(at -2.750058 -8.865108 180)
			(size 0.381 1.4478)
			(layers "F.Cu" "F.Mask" "F.Paste")
			(net "P3E_PCH_BMC_TX_C_DP")
		)
		(pad "A18" smd rect
			(at -2.750058 -8.264906 180)
			(size 0.381 1.4478)
			(layers "F.Cu" "F.Mask" "F.Paste")
			(net "P3E_PCH_BMC_TX_C_DN")
		)
		(pad "A19" smd rect
			(at -2.750058 -7.664958 180)
			(size 0.381 1.4478)
			(layers "F.Cu" "F.Mask" "F.Paste")
			(net "GND")
		)
		(pad "A20" smd rect
			(at -2.750058 -7.06501 180)
			(size 0.381 1.4478)
			(layers "F.Cu" "F.Mask" "F.Paste")
			(net "P3E_PCH_BMC_RX_DP")
		)
		(pad "A21" smd rect
			(at -2.750058 -6.465062 180)
			(size 0.381 1.4478)
			(layers "F.Cu" "F.Mask" "F.Paste")
			(net "P3E_PCH_BMC_RX_DN")
		)
		(pad "A22" smd rect
			(at -2.750058 -5.865114 180)
			(size 0.381 1.4478)
			(layers "F.Cu" "F.Mask" "F.Paste")
			(net "GND")
		)
		(pad "A23" smd rect
			(at -2.750058 -5.264912 180)
			(size 0.381 1.4478)
			(layers "F.Cu" "F.Mask" "F.Paste")
			(net "SMB_PCIE0_3V3AUX_SCL")
		)
		(pad "A24" smd rect
			(at -2.750058 -4.664964 180)
			(size 0.381 1.4478)
			(layers "F.Cu" "F.Mask" "F.Paste")
			(net "SMB_PCIE0_3V3AUX_SDA")
		)
		(pad "A25" smd rect
			(at -2.750058 -4.065016 180)
			(size 0.381 1.4478)
			(layers "F.Cu" "F.Mask" "F.Paste")
			(net "SMB_SML0_3V3AUX_SCL_R1")
		)
		(pad "A26" smd rect
			(at -2.750058 -3.465068 180)
			(size 0.381 1.4478)
			(layers "F.Cu" "F.Mask" "F.Paste")
			(net "SMB_SML0_3V3AUX_SDA_R1")
		)
		(pad "A27" smd rect
			(at -2.750058 -2.86512 180)
			(size 0.381 1.4478)
			(layers "F.Cu" "F.Mask" "F.Paste")
			(net "SMB_1_PLD_3V3AUX_SCL_R3")
		)
		(pad "A28" smd rect
			(at -2.750058 -2.264918 180)
			(size 0.381 1.4478)
			(layers "F.Cu" "F.Mask" "F.Paste")
			(net "SMB_1_PLD_3V3AUX_SDA_R3")
		)
		(pad "A29" smd rect
			(at -2.750058 1.74498 180)
			(size 0.381 1.4478)
			(layers "F.Cu" "F.Mask" "F.Paste")
			(net "SMB_FAN_3V3AUX_SCL")
		)
		(pad "A30" smd rect
			(at -2.750058 2.344928 180)
			(size 0.381 1.4478)
			(layers "F.Cu" "F.Mask" "F.Paste")
			(net "SMB_FAN_3V3AUX_SDA")
		)
		(pad "A31" smd rect
			(at -2.750058 2.944876 180)
			(size 0.381 1.4478)
			(layers "F.Cu" "F.Mask" "F.Paste")
			(net "SMB_PCIE2_3V3AUX_SCL_R0")
		)
		(pad "A32" smd rect
			(at -2.750058 3.545078 180)
			(size 0.381 1.4478)
			(layers "F.Cu" "F.Mask" "F.Paste")
			(net "SMB_PCIE2_3V3AUX_SDA_R0")
		)
		(pad "A33" smd rect
			(at -2.750058 4.145026 180)
			(size 0.381 1.4478)
			(layers "F.Cu" "F.Mask" "F.Paste")
			(net "GND")
		)
		(pad "A34" smd rect
			(at -2.750058 4.744974 180)
			(size 0.381 1.4478)
			(layers "F.Cu" "F.Mask" "F.Paste")
			(net "JTAG_BMC_TCK")
		)
		(pad "A35" smd rect
			(at -2.750058 5.344922 180)
			(size 0.381 1.4478)
			(layers "F.Cu" "F.Mask" "F.Paste")
			(net "JTAG_BMC_TMS")
		)
		(pad "A36" smd rect
			(at -2.750058 5.945124 180)
			(size 0.381 1.4478)
			(layers "F.Cu" "F.Mask" "F.Paste")
			(net "JTAG_BMC_TDI")
		)
		(pad "A37" smd rect
			(at -2.750058 6.545072 180)
			(size 0.381 1.4478)
			(layers "F.Cu" "F.Mask" "F.Paste")
			(net "JTAG_BMC_TDO")
		)
		(pad "A38" smd rect
			(at -2.750058 7.14502 180)
			(size 0.381 1.4478)
			(layers "F.Cu" "F.Mask" "F.Paste")
			(net "SMB_PCIE3_3V3AUX_SCL_R")
		)
		(pad "A39" smd rect
			(at -2.750058 7.744968 180)
			(size 0.381 1.4478)
			(layers "F.Cu" "F.Mask" "F.Paste")
			(net "SMB_PCIE3_3V3AUX_SDA_R")
		)
		(pad "A40" smd rect
			(at -2.750058 8.344916 180)
			(size 0.381 1.4478)
			(layers "F.Cu" "F.Mask" "F.Paste")
			(net "SMB_S3M_CPU_3V3AUX_SCL_R0")
		)
		(pad "A41" smd rect
			(at -2.750058 8.945118 180)
			(size 0.381 1.4478)
			(layers "F.Cu" "F.Mask" "F.Paste")
			(net "SMB_S3M_CPU_3V3AUX_SDA_R0")
		)
		(pad "A42" smd rect
			(at -2.750058 9.545066 180)
			(size 0.381 1.4478)
			(layers "F.Cu" "F.Mask" "F.Paste")
			(net "GND")
		)
		(pad "A43" smd rect
			(at -2.750058 14.454886 180)
			(size 0.381 1.4478)
			(layers "F.Cu" "F.Mask" "F.Paste")
			(net "FM_JTAG_BMC_MUX_SEL_FROM_BMC_R2")
		)
		(pad "A44" smd rect
			(at -2.750058 15.055088 180)
			(size 0.381 1.4478)
			(layers "F.Cu" "F.Mask" "F.Paste")
			(net "PWRGD_PS_PWROK_R")
		)
		(pad "A45" smd rect
			(at -2.750058 15.655036 180)
			(size 0.381 1.4478)
			(layers "F.Cu" "F.Mask" "F.Paste")
			(net "TP_HPM_STBY_EN")
		)
		(pad "A46" smd rect
			(at -2.750058 16.254984 180)
			(size 0.381 1.4478)
			(layers "F.Cu" "F.Mask" "F.Paste")
			(net "RST_MB_STBY_N")
		)
		(pad "A47" smd rect
			(at -2.750058 16.854932 180)
			(size 0.381 1.4478)
			(layers "F.Cu" "F.Mask" "F.Paste")
			(net "FM_BMC_PWRBTN_OUT_R_N")
		)
		(pad "A48" smd rect
			(at -2.750058 17.45488 180)
			(size 0.381 1.4478)
			(layers "F.Cu" "F.Mask" "F.Paste")
			(net "PWRGD_SYS_PWROK")
		)
		(pad "A49" smd rect
			(at -2.750058 18.055082 180)
			(size 0.381 1.4478)
			(layers "F.Cu" "F.Mask" "F.Paste")
			(net "JTAG_BMC_DBP_PREQ_N")
		)
		(pad "A50" smd rect
			(at -2.750058 18.65503 180)
			(size 0.381 1.4478)
			(layers "F.Cu" "F.Mask" "F.Paste")
			(net "JTAG_DBP_BMC_PRDY_N")
		)
		(pad "A51" smd rect
			(at -2.750058 19.254978 180)
			(size 0.381 1.4478)
			(layers "F.Cu" "F.Mask" "F.Paste")
			(net "RST_PLTRST_B_N")
		)
		(pad "A52" smd rect
			(at -2.750058 19.854926 180)
			(size 0.381 1.4478)
			(layers "F.Cu" "F.Mask" "F.Paste")
			(net "FM_UARTSW_MSB_R")
		)
		(pad "A53" smd rect
			(at -2.750058 20.455128 180)
			(size 0.381 1.4478)
			(layers "F.Cu" "F.Mask" "F.Paste")
			(net "ROT_P1_RST_IND_N")
		)
		(pad "A54" smd rect
			(at -2.750058 21.055076 180)
			(size 0.381 1.4478)
			(layers "F.Cu" "F.Mask" "F.Paste")
			(net "FM_BMC_INTRUDER_N")
		)
		(pad "A55" smd rect
			(at -2.750058 21.655024 180)
			(size 0.381 1.4478)
			(layers "F.Cu" "F.Mask" "F.Paste")
			(net "FM_UARTSW_LSB_R")
		)
		(pad "A56" smd rect
			(at -2.750058 22.254972 180)
			(size 0.381 1.4478)
			(layers "F.Cu" "F.Mask" "F.Paste")
			(net "IRQ0_A57")
		)
		(pad "A57" smd rect
			(at -2.750058 22.85492 180)
			(size 0.381 1.4478)
			(layers "F.Cu" "F.Mask" "F.Paste")
			(net "FM_SCM_PRSNT1_N")
		)
		(pad "A58" smd rect
			(at -2.750058 23.455122 180)
			(size 0.381 1.4478)
			(layers "F.Cu" "F.Mask" "F.Paste")
			(net "GND")
		)
		(pad "A59" smd rect
			(at -2.750058 24.05507 180)
			(size 0.381 1.4478)
			(layers "F.Cu" "F.Mask" "F.Paste")
			(net "USB3_PCH_RX_DP<4>")
		)
		(pad "A60" smd rect
			(at -2.750058 24.655018 180)
			(size 0.381 1.4478)
			(layers "F.Cu" "F.Mask" "F.Paste")
			(net "USB3_PCH_RX_DN<4>")
		)
		(pad "A61" smd rect
			(at -2.750058 25.254966 180)
			(size 0.381 1.4478)
			(layers "F.Cu" "F.Mask" "F.Paste")
			(net "GND")
		)
		(pad "A62" smd rect
			(at -2.750058 25.854914 180)
			(size 0.381 1.4478)
			(layers "F.Cu" "F.Mask" "F.Paste")
			(net "TP_PCIE_HPM_RXP<1>")
		)
		(pad "A63" smd rect
			(at -2.750058 26.455116 180)
			(size 0.381 1.4478)
			(layers "F.Cu" "F.Mask" "F.Paste")
			(net "TP_PCIE_HPM_RXN<1>")
		)
		(pad "A64" smd rect
			(at -2.750058 27.055064 180)
			(size 0.381 1.4478)
			(layers "F.Cu" "F.Mask" "F.Paste")
			(net "GND")
		)
		(pad "A65" smd rect
			(at -2.750058 27.655012 180)
			(size 0.381 1.4478)
			(layers "F.Cu" "F.Mask" "F.Paste")
			(net "P2E_MB_BMC_RX_BUF_DP<0>")
		)
		(pad "A66" smd rect
			(at -2.750058 28.25496 180)
			(size 0.381 1.4478)
			(layers "F.Cu" "F.Mask" "F.Paste")
			(net "P2E_MB_BMC_RX_BUF_DN<0>")
		)
		(pad "A67" smd rect
			(at -2.750058 28.854908 180)
			(size 0.381 1.4478)
			(layers "F.Cu" "F.Mask" "F.Paste")
			(net "GND")
		)
		(pad "A68" smd rect
			(at -2.750058 29.45511 180)
			(size 0.381 1.4478)
			(layers "F.Cu" "F.Mask" "F.Paste")
			(net "CLK_100M_BMC_RC_DP")
		)
		(pad "A69" smd rect
			(at -2.750058 30.055058 180)
			(size 0.381 1.4478)
			(layers "F.Cu" "F.Mask" "F.Paste")
			(net "CLK_100M_BMC_RC_DN")
		)
		(pad "A70" smd rect
			(at -2.750058 30.655006 180)
			(size 0.381 1.4478)
			(layers "F.Cu" "F.Mask" "F.Paste")
			(net "GND")
		)
		(pad "B1" smd rect
			(at -5.700014 -18.465038 180)
			(size 0.381 1.4478)
			(layers "F.Cu" "F.Mask" "F.Paste")
			(net "ESPI_HOST_LPC_BMC_CLK")
		)
		(pad "B2" smd rect
			(at -5.700014 -17.86509 180)
			(size 0.381 1.4478)
			(layers "F.Cu" "F.Mask" "F.Paste")
			(net "ESPI_HOST_LPC_BMC_LFRAME_N")
		)
		(pad "B3" smd rect
			(at -5.700014 -17.264888 180)
			(size 0.381 1.4478)
			(layers "F.Cu" "F.Mask" "F.Paste")
			(net "IRQ_ESPI_LPC_SERIRQ_ALERT_R_N")
		)
		(pad "B4" smd rect
			(at -5.700014 -16.66494 180)
			(size 0.381 1.4478)
			(layers "F.Cu" "F.Mask" "F.Paste")
			(net "ESPI_BMC_LPC_RST_N")
		)
		(pad "B5" smd rect
			(at -5.700014 -16.064992 180)
			(size 0.381 1.4478)
			(layers "F.Cu" "F.Mask" "F.Paste")
			(net "ESPI_LPC_LAD0_IO0")
		)
		(pad "B6" smd rect
			(at -5.700014 -15.465044 180)
			(size 0.381 1.4478)
			(layers "F.Cu" "F.Mask" "F.Paste")
			(net "ESPI_LPC_LAD0_IO1")
		)
		(pad "B7" smd rect
			(at -5.700014 -14.865096 180)
			(size 0.381 1.4478)
			(layers "F.Cu" "F.Mask" "F.Paste")
			(net "ESPI_LPC_LAD0_IO2")
		)
		(pad "B8" smd rect
			(at -5.700014 -14.264894 180)
			(size 0.381 1.4478)
			(layers "F.Cu" "F.Mask" "F.Paste")
			(net "ESPI_LPC_LAD0_IO3")
		)
		(pad "B9" smd rect
			(at -5.700014 -13.664946 180)
			(size 0.381 1.4478)
			(layers "F.Cu" "F.Mask" "F.Paste")
			(net "FM_LPC_ESPI_SEL")
		)
		(pad "B10" smd rect
			(at -5.700014 -13.064998 180)
			(size 0.381 1.4478)
			(layers "F.Cu" "F.Mask" "F.Paste")
			(net "GND")
		)
		(pad "B11" smd rect
			(at -5.700014 -12.46505 180)
			(size 0.381 1.4478)
			(layers "F.Cu" "F.Mask" "F.Paste")
			(net "SPI_SYS_CLK")
		)
		(pad "B12" smd rect
			(at -5.700014 -11.865102 180)
			(size 0.381 1.4478)
			(layers "F.Cu" "F.Mask" "F.Paste")
			(net "SPI_SYS_CS0_N")
		)
		(pad "B13" smd rect
			(at -5.700014 -11.2649 180)
			(size 0.381 1.4478)
			(layers "F.Cu" "F.Mask" "F.Paste")
			(net "SPI_SYS_MOSI")
		)
		(pad "B14" smd rect
			(at -5.700014 -10.664952 180)
			(size 0.381 1.4478)
			(layers "F.Cu" "F.Mask" "F.Paste")
			(net "SPI_SYS_MISO")
		)
		(pad "B15" smd rect
			(at -5.700014 -10.065004 180)
			(size 0.381 1.4478)
			(layers "F.Cu" "F.Mask" "F.Paste")
			(net "SPI_SYS_WP_IO2")
		)
		(pad "B16" smd rect
			(at -5.700014 -9.465056 180)
			(size 0.381 1.4478)
			(layers "F.Cu" "F.Mask" "F.Paste")
			(net "SPI_SYS_HOLD_IO3")
		)
		(pad "B17" smd rect
			(at -5.700014 -8.865108 180)
			(size 0.381 1.4478)
			(layers "F.Cu" "F.Mask" "F.Paste")
			(net "GND")
		)
		(pad "B18" smd rect
			(at -5.700014 -8.264906 180)
			(size 0.381 1.4478)
			(layers "F.Cu" "F.Mask" "F.Paste")
			(net "CLK_50M_RMII_BMC_OCP")
		)
		(pad "B19" smd rect
			(at -5.700014 -7.664958 180)
			(size 0.381 1.4478)
			(layers "F.Cu" "F.Mask" "F.Paste")
			(net "RMII_OCP_BMC_CRSDV")
		)
		(pad "B20" smd rect
			(at -5.700014 -7.06501 180)
			(size 0.381 1.4478)
			(layers "F.Cu" "F.Mask" "F.Paste")
			(net "RMII_BMC_OCP_TX_EN")
		)
		(pad "B21" smd rect
			(at -5.700014 -6.465062 180)
			(size 0.381 1.4478)
			(layers "F.Cu" "F.Mask" "F.Paste")
			(net "RMII_BMC_OCP_TXD_0")
		)
		(pad "B22" smd rect
			(at -5.700014 -5.865114 180)
			(size 0.381 1.4478)
			(layers "F.Cu" "F.Mask" "F.Paste")
			(net "RMII_BMC_OCP_TXD_1")
		)
		(pad "B23" smd rect
			(at -5.700014 -5.264912 180)
			(size 0.381 1.4478)
			(layers "F.Cu" "F.Mask" "F.Paste")
			(net "RMII_BMC_OCP_RX_ER")
		)
		(pad "B24" smd rect
			(at -5.700014 -4.664964 180)
			(size 0.381 1.4478)
			(layers "F.Cu" "F.Mask" "F.Paste")
			(net "RMII_OCP_BMC_RXD_0")
		)
		(pad "B25" smd rect
			(at -5.700014 -4.065016 180)
			(size 0.381 1.4478)
			(layers "F.Cu" "F.Mask" "F.Paste")
			(net "RMII_OCP_BMC_RXD_1")
		)
		(pad "B26" smd rect
			(at -5.700014 -3.465068 180)
			(size 0.381 1.4478)
			(layers "F.Cu" "F.Mask" "F.Paste")
			(net "GND")
		)
		(pad "B27" smd rect
			(at -5.700014 -2.86512 180)
			(size 0.381 1.4478)
			(layers "F.Cu" "F.Mask" "F.Paste")
			(net "PECI_BMC")
		)
		(pad "B28" smd rect
			(at -5.700014 -2.264918 180)
			(size 0.381 1.4478)
			(layers "F.Cu" "F.Mask" "F.Paste")
			(net "PVCCIO_PECI_BMC")
		)
		(pad "B29" smd rect
			(at -5.700014 1.74498 180)
			(size 0.381 1.4478)
			(layers "F.Cu" "F.Mask" "F.Paste")
			(net "SGPIO_DO_0")
		)
		(pad "B30" smd rect
			(at -5.700014 2.344928 180)
			(size 0.381 1.4478)
			(layers "F.Cu" "F.Mask" "F.Paste")
			(net "SGPIO_CLK_0")
		)
		(pad "B31" smd rect
			(at -5.700014 2.944876 180)
			(size 0.381 1.4478)
			(layers "F.Cu" "F.Mask" "F.Paste")
			(net "SGPIO_DI_0")
		)
		(pad "B32" smd rect
			(at -5.700014 3.545078 180)
			(size 0.381 1.4478)
			(layers "F.Cu" "F.Mask" "F.Paste")
			(net "SGPIO_LD_0")
		)
		(pad "B33" smd rect
			(at -5.700014 4.145026 180)
			(size 0.381 1.4478)
			(layers "F.Cu" "F.Mask" "F.Paste")
			(net "GND")
		)
		(pad "B34" smd rect
			(at -5.700014 4.744974 180)
			(size 0.381 1.4478)
			(layers "F.Cu" "F.Mask" "F.Paste")
			(net "SGPIO_DO_1")
		)
		(pad "B35" smd rect
			(at -5.700014 5.344922 180)
			(size 0.381 1.4478)
			(layers "F.Cu" "F.Mask" "F.Paste")
			(net "SGPIO_CLK_1")
		)
	)
)
